G04*
G04 #@! TF.GenerationSoftware,Altium Limited,Altium Designer,23.6.0 (18)*
G04*
G04 Layer_Physical_Order=3*
G04 Layer_Color=16440176*
%FSLAX44Y44*%
%MOMM*%
G71*
G04*
G04 #@! TF.SameCoordinates,B62FFF2A-40BB-47C2-B022-6C0D6E2DF31E*
G04*
G04*
G04 #@! TF.FilePolarity,Positive*
G04*
G01*
G75*
%ADD65C,0.4064*%
%ADD66C,5.5000*%
G36*
X215000Y73809D02*
X213730Y73283D01*
X213214Y73799D01*
X212000Y74302D01*
X210686D01*
X209473Y73799D01*
X208544Y72870D01*
X208041Y71657D01*
Y70343D01*
X208544Y69130D01*
X209473Y68201D01*
X210686Y67698D01*
X212000D01*
X213214Y68201D01*
X213730Y68717D01*
X215000Y68191D01*
Y64466D01*
X214375Y64097D01*
X213730Y63857D01*
X212657Y64302D01*
X211343D01*
X210130Y63799D01*
X209201Y62870D01*
X208698Y61657D01*
Y60343D01*
X209201Y59130D01*
X210130Y58201D01*
X211343Y57698D01*
X212657D01*
X213730Y58142D01*
X214375Y57903D01*
X215000Y57534D01*
Y36362D01*
X213850Y35559D01*
X212875Y35463D01*
X212301Y35289D01*
X211714Y35172D01*
X209911Y34425D01*
X209275Y34000D01*
X196466D01*
X196097Y34625D01*
X195858Y35270D01*
X196302Y36343D01*
Y37657D01*
X195799Y38870D01*
X194870Y39799D01*
X193657Y40302D01*
X192343D01*
X191130Y39799D01*
X190201Y38870D01*
X189698Y37657D01*
Y36343D01*
X190142Y35270D01*
X189903Y34625D01*
X189534Y34000D01*
X174936D01*
X174123Y35217D01*
X172467Y36872D01*
X171144Y37757D01*
X171144Y37757D01*
X168981Y38652D01*
X168981Y38653D01*
X167421Y38963D01*
X165079D01*
X163519Y38653D01*
X163519Y38652D01*
X161356Y37757D01*
X160033Y36872D01*
X158377Y35217D01*
X157564Y34000D01*
X156120D01*
X155272Y35270D01*
X155302Y35343D01*
Y36657D01*
X154799Y37870D01*
X153870Y38799D01*
X152657Y39302D01*
X151343D01*
X150130Y38799D01*
X149201Y37870D01*
X148698Y36657D01*
Y35343D01*
X148728Y35270D01*
X147880Y34000D01*
X141120D01*
X140272Y35270D01*
X140302Y35343D01*
Y36657D01*
X139799Y37870D01*
X138870Y38799D01*
X137657Y39302D01*
X136343D01*
X135130Y38799D01*
X134201Y37870D01*
X133698Y36657D01*
Y35343D01*
X133728Y35270D01*
X132880Y34000D01*
X126531D01*
X126302Y34343D01*
Y35657D01*
X125799Y36870D01*
X124870Y37799D01*
X123657Y38302D01*
X122343D01*
X121130Y37799D01*
X120201Y36870D01*
X119698Y35657D01*
Y34343D01*
X119469Y34000D01*
X114531D01*
X114302Y34343D01*
Y35657D01*
X113799Y36870D01*
X112870Y37799D01*
X111657Y38302D01*
X110343D01*
X109130Y37799D01*
X108201Y36870D01*
X107698Y35657D01*
Y34343D01*
X107469Y34000D01*
X96302D01*
Y34657D01*
X95799Y35870D01*
X94870Y36799D01*
X93657Y37302D01*
X92343D01*
X91130Y36799D01*
X90201Y35870D01*
X89698Y34657D01*
Y34000D01*
X75290D01*
X74966Y34927D01*
X74940Y35270D01*
X75799Y36130D01*
X76302Y37343D01*
Y38657D01*
X75799Y39870D01*
X74870Y40799D01*
X73657Y41302D01*
X72343D01*
X71130Y40799D01*
X70201Y39870D01*
X69698Y38657D01*
Y37343D01*
X70201Y36130D01*
X71060Y35270D01*
X71034Y34927D01*
X70710Y34000D01*
X65290D01*
X64966Y34927D01*
X64940Y35270D01*
X65799Y36130D01*
X66302Y37343D01*
Y38657D01*
X65799Y39870D01*
X64870Y40799D01*
X63657Y41302D01*
X62343D01*
X61130Y40799D01*
X60201Y39870D01*
X59698Y38657D01*
Y37343D01*
X60201Y36130D01*
X61060Y35270D01*
X61034Y34927D01*
X60710Y34000D01*
X27000D01*
Y259000D01*
X118000D01*
Y378000D01*
X177534D01*
X177903Y377375D01*
X178143Y376730D01*
X177698Y375657D01*
Y374343D01*
X178201Y373130D01*
X179130Y372201D01*
X180343Y371698D01*
X181657D01*
X182870Y372201D01*
X183799Y373130D01*
X184302Y374343D01*
Y375657D01*
X183857Y376730D01*
X184097Y377375D01*
X184466Y378000D01*
X215000D01*
Y73809D01*
D02*
G37*
%LPC*%
G36*
X190657Y357302D02*
X189343D01*
X188130Y356799D01*
X187201Y355870D01*
X186698Y354657D01*
Y353343D01*
X187201Y352130D01*
X188130Y351201D01*
X189343Y350698D01*
X190657D01*
X191870Y351201D01*
X192799Y352130D01*
X193302Y353343D01*
Y354657D01*
X192799Y355870D01*
X191870Y356799D01*
X190657Y357302D01*
D02*
G37*
G36*
X177657Y343302D02*
X176343D01*
X175130Y342799D01*
X174201Y341870D01*
X173698Y340657D01*
Y339343D01*
X174201Y338130D01*
X175130Y337201D01*
X176343Y336698D01*
X177657D01*
X178870Y337201D01*
X179799Y338130D01*
X180302Y339343D01*
Y340657D01*
X179799Y341870D01*
X178870Y342799D01*
X177657Y343302D01*
D02*
G37*
G36*
X133187Y322302D02*
X131873D01*
X130659Y321799D01*
X130328Y321467D01*
X129498Y321001D01*
X128668Y321467D01*
X128336Y321799D01*
X127123Y322302D01*
X125809D01*
X124595Y321799D01*
X123666Y320871D01*
X123164Y319657D01*
Y318343D01*
X123666Y317130D01*
X124595Y316201D01*
X125809Y315698D01*
X127123D01*
X128336Y316201D01*
X128668Y316533D01*
X129498Y316999D01*
X130328Y316533D01*
X130659Y316201D01*
X131873Y315698D01*
X133187D01*
X134400Y316201D01*
X135329Y317130D01*
X135832Y318343D01*
Y319657D01*
X135329Y320871D01*
X134400Y321799D01*
X133187Y322302D01*
D02*
G37*
G36*
X159657Y325302D02*
X158343D01*
X157130Y324799D01*
X156201Y323870D01*
X155698Y322657D01*
Y321343D01*
X156201Y320130D01*
X157130Y319201D01*
X158343Y318698D01*
X159657D01*
X160870Y319201D01*
X161799Y320130D01*
X162302Y321343D01*
Y322657D01*
X161799Y323870D01*
X160870Y324799D01*
X159657Y325302D01*
D02*
G37*
G36*
X206657Y279302D02*
X205343D01*
X204130Y278799D01*
X203201Y277870D01*
X202698Y276657D01*
Y275343D01*
X203201Y274130D01*
X204130Y273201D01*
X205343Y272698D01*
X206657D01*
X207870Y273201D01*
X208799Y274130D01*
X209302Y275343D01*
Y276657D01*
X208799Y277870D01*
X207870Y278799D01*
X206657Y279302D01*
D02*
G37*
G36*
Y271302D02*
X205343D01*
X204130Y270799D01*
X203201Y269870D01*
X202698Y268657D01*
Y267343D01*
X203201Y266130D01*
X204130Y265201D01*
X205343Y264698D01*
X206657D01*
X207870Y265201D01*
X208799Y266130D01*
X209302Y267343D01*
Y268657D01*
X208799Y269870D01*
X207870Y270799D01*
X206657Y271302D01*
D02*
G37*
G36*
Y262302D02*
X205343D01*
X204130Y261799D01*
X203201Y260870D01*
X202698Y259657D01*
Y258343D01*
X203201Y257130D01*
X204130Y256201D01*
X205343Y255698D01*
X206657D01*
X207870Y256201D01*
X208799Y257130D01*
X209302Y258343D01*
Y259657D01*
X208799Y260870D01*
X207870Y261799D01*
X206657Y262302D01*
D02*
G37*
G36*
X205657Y242302D02*
X204343D01*
X203130Y241799D01*
X202201Y240870D01*
X201698Y239657D01*
Y238343D01*
X202201Y237130D01*
X203130Y236201D01*
X204343Y235698D01*
X205657D01*
X206870Y236201D01*
X207799Y237130D01*
X208302Y238343D01*
Y239657D01*
X207799Y240870D01*
X206870Y241799D01*
X205657Y242302D01*
D02*
G37*
G36*
X206657Y218302D02*
X205343D01*
X204130Y217799D01*
X203201Y216870D01*
X202698Y215657D01*
Y214343D01*
X203201Y213130D01*
X204130Y212201D01*
X205343Y211698D01*
X206657D01*
X207870Y212201D01*
X208799Y213130D01*
X209302Y214343D01*
Y215657D01*
X208799Y216870D01*
X207870Y217799D01*
X206657Y218302D01*
D02*
G37*
G36*
X208657Y196302D02*
X207343D01*
X206130Y195799D01*
X205201Y194870D01*
X204698Y193657D01*
Y192343D01*
X205201Y191130D01*
X206130Y190201D01*
X207343Y189698D01*
X208657D01*
X209870Y190201D01*
X210799Y191130D01*
X211302Y192343D01*
Y193657D01*
X210799Y194870D01*
X209870Y195799D01*
X208657Y196302D01*
D02*
G37*
G36*
X202867Y177302D02*
X201553D01*
X200340Y176799D01*
X199411Y175870D01*
X198908Y174657D01*
Y173343D01*
X199411Y172130D01*
X200340Y171201D01*
X201553Y170698D01*
X202867D01*
X204080Y171201D01*
X205009Y172130D01*
X205512Y173343D01*
Y174657D01*
X205009Y175870D01*
X204080Y176799D01*
X202867Y177302D01*
D02*
G37*
G36*
X50657Y164302D02*
X49343D01*
X48130Y163799D01*
X47201Y162870D01*
X46698Y161657D01*
Y160343D01*
X47201Y159130D01*
X48130Y158201D01*
X49343Y157698D01*
X50657D01*
X51870Y158201D01*
X52799Y159130D01*
X53302Y160343D01*
Y161657D01*
X52799Y162870D01*
X51870Y163799D01*
X50657Y164302D01*
D02*
G37*
G36*
X39667Y163500D02*
X38354D01*
X37140Y162997D01*
X36211Y162068D01*
X35708Y160855D01*
Y159541D01*
X36211Y158328D01*
X37140Y157399D01*
X38354Y156896D01*
X39667D01*
X40881Y157399D01*
X41810Y158328D01*
X42312Y159541D01*
Y160855D01*
X41810Y162068D01*
X40881Y162997D01*
X39667Y163500D01*
D02*
G37*
G36*
X188657Y163302D02*
X187343D01*
X186130Y162799D01*
X185201Y161870D01*
X184698Y160657D01*
Y159343D01*
X185201Y158130D01*
X186130Y157201D01*
X187343Y156698D01*
X188657D01*
X189870Y157201D01*
X190799Y158130D01*
X191302Y159343D01*
Y160657D01*
X190799Y161870D01*
X189870Y162799D01*
X188657Y163302D01*
D02*
G37*
G36*
X202867Y162062D02*
X201553D01*
X200340Y161559D01*
X199411Y160630D01*
X198908Y159417D01*
Y158103D01*
X199411Y156890D01*
X200340Y155961D01*
X201553Y155458D01*
X202867D01*
X204080Y155961D01*
X205009Y156890D01*
X205512Y158103D01*
Y159417D01*
X205009Y160630D01*
X204080Y161559D01*
X202867Y162062D01*
D02*
G37*
G36*
X188657Y151302D02*
X187343D01*
X186130Y150799D01*
X185201Y149870D01*
X184698Y148657D01*
Y147343D01*
X185201Y146130D01*
X186130Y145201D01*
X187343Y144698D01*
X188657D01*
X189870Y145201D01*
X190799Y146130D01*
X191302Y147343D01*
Y148657D01*
X190799Y149870D01*
X189870Y150799D01*
X188657Y151302D01*
D02*
G37*
G36*
X39657Y150302D02*
X38343D01*
X37130Y149799D01*
X36201Y148870D01*
X35698Y147657D01*
Y146343D01*
X36201Y145130D01*
X37130Y144201D01*
X38343Y143698D01*
X39657D01*
X40870Y144201D01*
X41799Y145130D01*
X42302Y146343D01*
Y147657D01*
X41799Y148870D01*
X40870Y149799D01*
X39657Y150302D01*
D02*
G37*
G36*
X202867Y146822D02*
X201553D01*
X200340Y146319D01*
X199411Y145390D01*
X198908Y144177D01*
Y142863D01*
X199411Y141650D01*
X200340Y140721D01*
X201553Y140218D01*
X202867D01*
X204080Y140721D01*
X205009Y141650D01*
X205512Y142863D01*
Y144177D01*
X205009Y145390D01*
X204080Y146319D01*
X202867Y146822D01*
D02*
G37*
G36*
X125657Y140052D02*
X124343D01*
X123130Y139549D01*
X122201Y138620D01*
X121698Y137407D01*
Y136093D01*
X122201Y134880D01*
X123130Y133951D01*
X124343Y133448D01*
X125657D01*
X126870Y133951D01*
X127799Y134880D01*
X128302Y136093D01*
Y137407D01*
X127799Y138620D01*
X126870Y139549D01*
X125657Y140052D01*
D02*
G37*
G36*
X94657D02*
X93343D01*
X92130Y139549D01*
X91201Y138620D01*
X90698Y137407D01*
Y136093D01*
X91201Y134880D01*
X92130Y133951D01*
X93343Y133448D01*
X94657D01*
X95870Y133951D01*
X96799Y134880D01*
X97302Y136093D01*
Y137407D01*
X96799Y138620D01*
X95870Y139549D01*
X94657Y140052D01*
D02*
G37*
G36*
X188657Y139302D02*
X187343D01*
X186130Y138799D01*
X185201Y137870D01*
X184698Y136657D01*
Y135343D01*
X185201Y134130D01*
X186130Y133201D01*
X187343Y132698D01*
X188657D01*
X189870Y133201D01*
X190799Y134130D01*
X191302Y135343D01*
Y136657D01*
X190799Y137870D01*
X189870Y138799D01*
X188657Y139302D01*
D02*
G37*
G36*
X198657Y129302D02*
X197343D01*
X196130Y128799D01*
X195201Y127870D01*
X194698Y126657D01*
Y125343D01*
X195201Y124130D01*
X196130Y123201D01*
X197343Y122698D01*
X198657D01*
X199870Y123201D01*
X200799Y124130D01*
X201302Y125343D01*
Y126657D01*
X200799Y127870D01*
X199870Y128799D01*
X198657Y129302D01*
D02*
G37*
G36*
X70125Y124347D02*
X68812D01*
X67598Y123844D01*
X66669Y122915D01*
X66167Y121701D01*
Y120388D01*
X66669Y119174D01*
X67598Y118245D01*
X68812Y117743D01*
X70125D01*
X71339Y118245D01*
X72268Y119174D01*
X72771Y120388D01*
Y121701D01*
X72268Y122915D01*
X71339Y123844D01*
X70125Y124347D01*
D02*
G37*
G36*
X198657Y120302D02*
X197343D01*
X196130Y119799D01*
X195201Y118870D01*
X194698Y117657D01*
Y116343D01*
X195201Y115130D01*
X196130Y114201D01*
X197343Y113698D01*
X198657D01*
X199870Y114201D01*
X200799Y115130D01*
X201302Y116343D01*
Y117657D01*
X200799Y118870D01*
X199870Y119799D01*
X198657Y120302D01*
D02*
G37*
G36*
X50657Y118302D02*
X49343D01*
X48130Y117799D01*
X47201Y116870D01*
X46698Y115657D01*
Y114343D01*
X47201Y113130D01*
X48130Y112201D01*
X49343Y111698D01*
X50657D01*
X51870Y112201D01*
X52799Y113130D01*
X53302Y114343D01*
Y115657D01*
X52799Y116870D01*
X51870Y117799D01*
X50657Y118302D01*
D02*
G37*
G36*
X40657Y117302D02*
X39343D01*
X38130Y116799D01*
X37201Y115870D01*
X36698Y114657D01*
Y113343D01*
X37201Y112130D01*
X38130Y111201D01*
X39343Y110698D01*
X40657D01*
X41870Y111201D01*
X42799Y112130D01*
X43302Y113343D01*
Y114657D01*
X42799Y115870D01*
X41870Y116799D01*
X40657Y117302D01*
D02*
G37*
G36*
X106657Y109302D02*
X105343D01*
X104130Y108799D01*
X103201Y107870D01*
X102698Y106657D01*
Y105343D01*
X103201Y104130D01*
X104130Y103201D01*
X105343Y102698D01*
X106657D01*
X107870Y103201D01*
X108799Y104130D01*
X109302Y105343D01*
Y106657D01*
X108799Y107870D01*
X107870Y108799D01*
X106657Y109302D01*
D02*
G37*
G36*
X199657Y104302D02*
X198343D01*
X197130Y103799D01*
X196201Y102870D01*
X195698Y101657D01*
Y100343D01*
X196201Y99130D01*
X197130Y98201D01*
X198343Y97698D01*
X199657D01*
X200870Y98201D01*
X201799Y99130D01*
X202302Y100343D01*
Y101657D01*
X201799Y102870D01*
X200870Y103799D01*
X199657Y104302D01*
D02*
G37*
G36*
Y93302D02*
X198343D01*
X197130Y92799D01*
X196201Y91870D01*
X195698Y90657D01*
Y89343D01*
X196201Y88130D01*
X197130Y87201D01*
X198343Y86698D01*
X199657D01*
X200870Y87201D01*
X201799Y88130D01*
X202302Y89343D01*
Y90657D01*
X201799Y91870D01*
X200870Y92799D01*
X199657Y93302D01*
D02*
G37*
G36*
X78657Y89302D02*
X77343D01*
X76130Y88799D01*
X75201Y87870D01*
X74698Y86657D01*
Y85343D01*
X75201Y84130D01*
X76130Y83201D01*
X77343Y82698D01*
X78657D01*
X79870Y83201D01*
X80799Y84130D01*
X81302Y85343D01*
Y86657D01*
X80799Y87870D01*
X79870Y88799D01*
X78657Y89302D01*
D02*
G37*
G36*
X38657Y87302D02*
X37343D01*
X36130Y86799D01*
X35201Y85870D01*
X34698Y84657D01*
Y83343D01*
X35201Y82130D01*
X36130Y81201D01*
X37343Y80698D01*
X38657D01*
X39870Y81201D01*
X40799Y82130D01*
X41302Y83343D01*
Y84657D01*
X40799Y85870D01*
X39870Y86799D01*
X38657Y87302D01*
D02*
G37*
G36*
X208450Y82309D02*
X207137D01*
X205923Y81806D01*
X204994Y80877D01*
X204492Y79664D01*
X204492Y79201D01*
X203302Y79007D01*
X203133Y79415D01*
X202799Y80220D01*
X201870Y81149D01*
X200657Y81652D01*
X199343D01*
X198130Y81149D01*
X197201Y80220D01*
X196698Y79007D01*
Y77693D01*
X197201Y76480D01*
X198130Y75551D01*
X199343Y75048D01*
X200657D01*
X201870Y75551D01*
X202799Y76480D01*
X203302Y77693D01*
X203302Y78156D01*
X204492Y78350D01*
X204661Y77942D01*
X204994Y77136D01*
X205923Y76207D01*
X207137Y75705D01*
X208450D01*
X209664Y76207D01*
X210593Y77136D01*
X211096Y78350D01*
Y79664D01*
X210593Y80877D01*
X209664Y81806D01*
X208450Y82309D01*
D02*
G37*
G36*
X187752Y67302D02*
X186439D01*
X185225Y66799D01*
X184893Y66467D01*
X184063Y66001D01*
X183234Y66467D01*
X182902Y66799D01*
X181688Y67302D01*
X180375D01*
X179161Y66799D01*
X178232Y65870D01*
X177729Y64657D01*
Y63343D01*
X178232Y62130D01*
X179161Y61201D01*
X180375Y60698D01*
X181688D01*
X182902Y61201D01*
X183234Y61533D01*
X184063Y61999D01*
X184893Y61533D01*
X185225Y61201D01*
X186439Y60698D01*
X187752D01*
X188966Y61201D01*
X189895Y62130D01*
X190397Y63343D01*
Y64657D01*
X189895Y65870D01*
X188966Y66799D01*
X187752Y67302D01*
D02*
G37*
G36*
X203769Y65298D02*
X202455D01*
X201241Y64796D01*
X200312Y63867D01*
X199810Y62653D01*
Y61340D01*
X200312Y60126D01*
X201241Y59197D01*
X202455Y58694D01*
X203769D01*
X204982Y59197D01*
X205911Y60126D01*
X206414Y61340D01*
Y62653D01*
X205911Y63867D01*
X204982Y64796D01*
X203769Y65298D01*
D02*
G37*
G36*
X80657Y52302D02*
X79343D01*
X78130Y51799D01*
X77201Y50870D01*
X76698Y49657D01*
Y48343D01*
X77201Y47130D01*
X78130Y46201D01*
X79343Y45698D01*
X80657D01*
X81870Y46201D01*
X82799Y47130D01*
X83302Y48343D01*
Y49657D01*
X82799Y50870D01*
X81870Y51799D01*
X80657Y52302D01*
D02*
G37*
G36*
X45657D02*
X44343D01*
X43130Y51799D01*
X42201Y50870D01*
X41698Y49657D01*
Y48343D01*
X42201Y47130D01*
X43130Y46201D01*
X44343Y45698D01*
X45657D01*
X46870Y46201D01*
X47799Y47130D01*
X48302Y48343D01*
Y49657D01*
X47799Y50870D01*
X46870Y51799D01*
X45657Y52302D01*
D02*
G37*
G36*
X118657Y50302D02*
X117343D01*
X116130Y49799D01*
X115201Y48870D01*
X114698Y47657D01*
Y46343D01*
X115201Y45130D01*
X116130Y44201D01*
X117343Y43698D01*
X118657D01*
X119870Y44201D01*
X120799Y45130D01*
X121302Y46343D01*
Y47657D01*
X120799Y48870D01*
X119870Y49799D01*
X118657Y50302D01*
D02*
G37*
G36*
X56657Y48302D02*
X55343D01*
X54130Y47799D01*
X53201Y46870D01*
X52698Y45657D01*
Y44343D01*
X53201Y43130D01*
X54130Y42201D01*
X55343Y41698D01*
X56657D01*
X57870Y42201D01*
X58799Y43130D01*
X59302Y44343D01*
Y45657D01*
X58799Y46870D01*
X57870Y47799D01*
X56657Y48302D01*
D02*
G37*
G36*
X196844Y54474D02*
X195530D01*
X194316Y53972D01*
X193388Y53043D01*
X192885Y51829D01*
Y50516D01*
X193388Y49302D01*
X193879Y48811D01*
X193984Y47690D01*
X193773Y47257D01*
X193074Y46558D01*
X192571Y45345D01*
Y44031D01*
X193074Y42818D01*
X194003Y41889D01*
X195216Y41386D01*
X196530D01*
X197744Y41889D01*
X198672Y42818D01*
X199175Y44031D01*
Y45345D01*
X198672Y46558D01*
X198181Y47050D01*
X198076Y48170D01*
X198287Y48603D01*
X198986Y49302D01*
X199489Y50516D01*
Y51829D01*
X198986Y53043D01*
X198057Y53972D01*
X196844Y54474D01*
D02*
G37*
G36*
X176657Y47302D02*
X175343D01*
X174130Y46799D01*
X173201Y45870D01*
X172698Y44657D01*
Y43343D01*
X173201Y42130D01*
X174130Y41201D01*
X175343Y40698D01*
X176657D01*
X177870Y41201D01*
X178799Y42130D01*
X179302Y43343D01*
Y44657D01*
X178799Y45870D01*
X177870Y46799D01*
X176657Y47302D01*
D02*
G37*
%LPD*%
D65*
X69468Y121045D02*
D03*
X40000Y114000D02*
D03*
X50000Y115000D02*
D03*
X39000Y147000D02*
D03*
X118000Y47000D02*
D03*
X200000Y78350D02*
D03*
X207794Y79007D02*
D03*
X203112Y61996D02*
D03*
X211343Y71000D02*
D03*
X212000Y61000D02*
D03*
X63000Y38000D02*
D03*
X193000Y37000D02*
D03*
X208000Y193000D02*
D03*
X205000Y239000D02*
D03*
X206000Y215000D02*
D03*
Y259000D02*
D03*
Y268000D02*
D03*
Y276000D02*
D03*
X213640Y410220D02*
D03*
X209830Y402600D02*
D03*
X213640Y394980D02*
D03*
X209830Y387360D02*
D03*
X206020Y410220D02*
D03*
X202210Y402600D02*
D03*
X206020Y394980D02*
D03*
X202210Y387360D02*
D03*
Y174000D02*
D03*
Y158760D02*
D03*
Y143520D02*
D03*
X198400Y410220D02*
D03*
X194590Y402600D02*
D03*
X198400Y394980D02*
D03*
X194590Y387360D02*
D03*
X190780Y410220D02*
D03*
X186970Y402600D02*
D03*
X190780Y394980D02*
D03*
X186970Y387360D02*
D03*
X183160Y410220D02*
D03*
X179350Y402600D02*
D03*
X183160Y394980D02*
D03*
X179350Y387360D02*
D03*
X175540Y410220D02*
D03*
X171730Y402600D02*
D03*
X175540Y394980D02*
D03*
X171730Y387360D02*
D03*
X167920Y410220D02*
D03*
X164110Y402600D02*
D03*
X167920Y394980D02*
D03*
X164110Y387360D02*
D03*
X160300Y410220D02*
D03*
X156490Y402600D02*
D03*
X160300Y394980D02*
D03*
X156490Y387360D02*
D03*
X152680Y410220D02*
D03*
X148870Y402600D02*
D03*
X152680Y394980D02*
D03*
X148870Y387360D02*
D03*
X145060Y410220D02*
D03*
X141250Y402600D02*
D03*
X145060Y394980D02*
D03*
X141250Y387360D02*
D03*
X137440Y394980D02*
D03*
X133630Y387360D02*
D03*
X126010D02*
D03*
X110770Y372120D02*
D03*
X106960Y379740D02*
D03*
X103150Y372120D02*
D03*
X106960Y364500D02*
D03*
X103150Y341640D02*
D03*
X95530Y387360D02*
D03*
X99340Y379740D02*
D03*
X95530Y372120D02*
D03*
X99340Y364500D02*
D03*
X95530Y341640D02*
D03*
Y311160D02*
D03*
Y295920D02*
D03*
Y280680D02*
D03*
X87910Y387360D02*
D03*
X91720Y379740D02*
D03*
X87910Y372120D02*
D03*
X91720Y364500D02*
D03*
X87910Y341640D02*
D03*
Y326400D02*
D03*
X91720Y303540D02*
D03*
Y288300D02*
D03*
X87910Y280680D02*
D03*
X91720Y273060D02*
D03*
X87910Y265440D02*
D03*
X80290Y402600D02*
D03*
X84100Y394980D02*
D03*
X80290Y387360D02*
D03*
X84100Y379740D02*
D03*
X80290Y372120D02*
D03*
X84100Y364500D02*
D03*
Y334020D02*
D03*
X80290Y326400D02*
D03*
Y280680D02*
D03*
X84100Y273060D02*
D03*
X80290Y265440D02*
D03*
X76480Y410220D02*
D03*
X72670Y402600D02*
D03*
X76480Y394980D02*
D03*
X72670Y387360D02*
D03*
X76480Y379740D02*
D03*
X72670Y372120D02*
D03*
X76480Y334020D02*
D03*
X72670Y326400D02*
D03*
X76480Y318780D02*
D03*
Y273060D02*
D03*
X72670Y265440D02*
D03*
X68860Y410220D02*
D03*
X65050Y402600D02*
D03*
X68860Y394980D02*
D03*
X65050Y387360D02*
D03*
X68860Y379740D02*
D03*
X65050Y372120D02*
D03*
X68860Y334020D02*
D03*
X65050Y326400D02*
D03*
X68860Y318780D02*
D03*
Y273060D02*
D03*
X65050Y265440D02*
D03*
X61240Y379740D02*
D03*
X57430Y372120D02*
D03*
X61240Y334020D02*
D03*
X57430Y326400D02*
D03*
Y280680D02*
D03*
X53620Y379740D02*
D03*
X49810Y372120D02*
D03*
Y280680D02*
D03*
X42190D02*
D03*
X46000Y273060D02*
D03*
X42190Y265440D02*
D03*
X38380Y410220D02*
D03*
X34570Y402600D02*
D03*
Y280680D02*
D03*
X38380Y273060D02*
D03*
X34570Y265440D02*
D03*
X30760Y410220D02*
D03*
X26950Y326400D02*
D03*
X30760Y318780D02*
D03*
X26950Y311160D02*
D03*
X30760Y303540D02*
D03*
X26950Y295920D02*
D03*
X30760Y288300D02*
D03*
X26950Y280680D02*
D03*
X30760Y273060D02*
D03*
X26950Y265440D02*
D03*
X19330Y372120D02*
D03*
X23140Y364500D02*
D03*
X19330Y356880D02*
D03*
X23140Y349260D02*
D03*
X19330Y341640D02*
D03*
X23140Y334020D02*
D03*
X19330Y326400D02*
D03*
X23140Y318780D02*
D03*
X19330Y311160D02*
D03*
X23140Y303540D02*
D03*
X19330Y295920D02*
D03*
X23140Y288300D02*
D03*
X19330Y280680D02*
D03*
X23140Y273060D02*
D03*
X19330Y265440D02*
D03*
Y250200D02*
D03*
Y234960D02*
D03*
Y219720D02*
D03*
Y204480D02*
D03*
Y189240D02*
D03*
Y174000D02*
D03*
Y158760D02*
D03*
Y143520D02*
D03*
Y128280D02*
D03*
Y113040D02*
D03*
Y97800D02*
D03*
Y82560D02*
D03*
Y67320D02*
D03*
X15520Y379740D02*
D03*
X11710Y372120D02*
D03*
X15520Y364500D02*
D03*
X11710Y356880D02*
D03*
X15520Y349260D02*
D03*
X11710Y341640D02*
D03*
X15520Y334020D02*
D03*
X11710Y326400D02*
D03*
X15520Y318780D02*
D03*
X11710Y311160D02*
D03*
X15520Y303540D02*
D03*
X11710Y295920D02*
D03*
X15520Y288300D02*
D03*
X11710Y280680D02*
D03*
X15520Y273060D02*
D03*
X11710Y265440D02*
D03*
X15520Y257820D02*
D03*
X11710Y250200D02*
D03*
X15520Y242580D02*
D03*
X11710Y234960D02*
D03*
X15520Y227340D02*
D03*
X11710Y219720D02*
D03*
X15520Y212100D02*
D03*
X11710Y204480D02*
D03*
X15520Y196860D02*
D03*
X11710Y189240D02*
D03*
X15520Y181620D02*
D03*
X11710Y174000D02*
D03*
X15520Y166380D02*
D03*
X11710Y158760D02*
D03*
X15520Y151140D02*
D03*
X11710Y143520D02*
D03*
X15520Y135900D02*
D03*
X11710Y128280D02*
D03*
X15520Y120660D02*
D03*
X11710Y113040D02*
D03*
X15520Y105420D02*
D03*
X11710Y97800D02*
D03*
X15520Y90180D02*
D03*
X11710Y82560D02*
D03*
X15520Y74940D02*
D03*
X11710Y67320D02*
D03*
X15520Y59700D02*
D03*
X32151Y339810D02*
D03*
X31576Y332800D02*
D03*
X35076Y326800D02*
D03*
X38651Y320417D02*
D03*
X43408Y314602D02*
D03*
X55998Y314097D02*
D03*
X54580Y320095D02*
D03*
X50238Y325800D02*
D03*
X47228Y332057D02*
D03*
X46887Y338234D02*
D03*
X46651Y344528D02*
D03*
X41962Y367714D02*
D03*
X39820Y373823D02*
D03*
X31485Y353188D02*
D03*
X30909Y359800D02*
D03*
X29145Y365800D02*
D03*
X33000Y393477D02*
D03*
X23000Y383750D02*
D03*
X24523Y377500D02*
D03*
X28054Y371915D02*
D03*
X31719Y347000D02*
D03*
X46267Y350969D02*
D03*
X43782Y379467D02*
D03*
X41000Y393477D02*
D03*
X9000Y395000D02*
D03*
Y408000D02*
D03*
X62000Y394000D02*
D03*
X73000Y38000D02*
D03*
X187096Y64000D02*
D03*
X181031D02*
D03*
X78000Y86000D02*
D03*
X132530Y319000D02*
D03*
X126466D02*
D03*
X112000Y77000D02*
D03*
X106000Y106000D02*
D03*
X117000Y121000D02*
D03*
X102000Y119000D02*
D03*
X125000Y136750D02*
D03*
X94000D02*
D03*
X38000Y84000D02*
D03*
X83000Y317000D02*
D03*
X159000Y322000D02*
D03*
X50000Y161000D02*
D03*
X190000Y354000D02*
D03*
X177000Y340000D02*
D03*
X181000Y375000D02*
D03*
X145000Y368000D02*
D03*
X135000D02*
D03*
X95000Y334000D02*
D03*
X79000Y360000D02*
D03*
X39010Y160198D02*
D03*
X64425Y314602D02*
D03*
X36000Y314802D02*
D03*
X199000Y90000D02*
D03*
Y101000D02*
D03*
X198000Y117000D02*
D03*
Y126000D02*
D03*
X188000Y136000D02*
D03*
Y148000D02*
D03*
Y160000D02*
D03*
X159000Y152000D02*
D03*
Y145500D02*
D03*
Y139375D02*
D03*
X176000Y44000D02*
D03*
X195873Y44688D02*
D03*
X196187Y51172D02*
D03*
X111000Y35000D02*
D03*
X204114Y40000D02*
D03*
X203458Y48255D02*
D03*
X211000Y40000D02*
D03*
Y47870D02*
D03*
X152000Y36000D02*
D03*
X137000D02*
D03*
X123000Y35000D02*
D03*
X93000Y34000D02*
D03*
X33000Y31000D02*
D03*
Y38000D02*
D03*
X32880Y45166D02*
D03*
X33000Y51645D02*
D03*
X15000Y50312D02*
D03*
X12791Y42000D02*
D03*
X6395Y41971D02*
D03*
X6826Y50312D02*
D03*
X80000Y49000D02*
D03*
X45000D02*
D03*
X56000Y45000D02*
D03*
D66*
X110000Y420000D02*
D03*
M02*
